# BASEBOARD_FAB2 (Tioga Pass) — schematic netlist excerpt (pin names and nets, part order shuffled) for the footprints in the layout excerpt that follows; sources: Cadence DE-HDL packaged netlist, KiCad conversion of Wiwynn_Tioga_Pass_MB.brd

U2T4  GTL2014  IC  pkg SM  page 93
  DIR  = PD_GTL2104_4_DIR
  B0  = H_CPU1_PROCHOT_G_R_N
  B1  = H_CPU0_PROCHOT_G_R_N
  VREF  = P0V7_GTL2104_5_VREF
  B2  = H_CPU_ERR1_GTL_N
  B3  = H_CPU_ERR0_GTL_N
  GND(0)  = GND
  GND(1)  = GND
  A3  = FM_CPU_ERR0_LVT3_R_N
  A2  = FM_CPU_ERR1_LVT3_R_N
  GND(2)  = GND
  A1  = FM_CPU0_PROCHOT_LVT3_R_N
  A0  = FM_CPU1_PROCHOT_LVT3_R_N
  VCC  = P3V3

C2P13  CAP_A  0.1UF 16V 10% X7R  pkg 0402V  page 188 : A = P12V_STBY ; B = GND

(kicad_pcb
	(version 20260206)
	(generator "pcbnew")
	(generator_version "10.0")
	(general
		(thickness 1.6)
		(legacy_teardrops no)
	)
	(paper "A4")
	(title_block
		(title "Wiwynn_Tioga_Pass_MB.brd")
		(comment 1 "Tioga Pass / footprints 2961-2962 of 4770")
	)
	(layers
		(0 "F.Cu" signal "TOP")
		(4 "In1.Cu" signal "L2GND")
		(6 "In2.Cu" signal "L3")
		(8 "In3.Cu" signal "L4GND")
		(10 "In4.Cu" signal "L5")
		(12 "In5.Cu" signal "L6GND")
		(14 "In6.Cu" signal "L7VCC")
		(16 "In7.Cu" signal "L8VCC")
		(18 "In8.Cu" signal "L9GND")
		(20 "In9.Cu" signal "L10")
		(22 "In10.Cu" signal "L11GND")
		(24 "In11.Cu" signal "L12")
		(26 "In12.Cu" signal "L13GND")
		(2 "B.Cu" signal "BOTTOM")
		(9 "F.Adhes" user "F.Adhesive")
		(11 "B.Adhes" user "B.Adhesive")
		(13 "F.Paste" user "Package Geometry/Pastemask Top")
		(15 "B.Paste" user "Package Geometry/Pastemask Bottom")
		(5 "F.SilkS" user "Ref Des/Silkscreen Top")
		(7 "B.SilkS" user "Ref Des/Silkscreen Bottom")
		(1 "F.Mask" user "Board Geometry/Soldermask Top")
		(3 "B.Mask" user "Board Geometry/Soldermask Bottom")
		(17 "Dwgs.User" user "User.Drawings")
		(19 "Cmts.User" user "User.Comments")
		(21 "Eco1.User" user "User.Eco1")
		(23 "Eco2.User" user "User.Eco2")
		(25 "Edge.Cuts" user "Board Geometry/Outline")
		(27 "Margin" user)
		(31 "F.CrtYd" user "Package Geometry/Place Bound Top")
		(29 "B.CrtYd" user "Package Geometry/Place Bound Bottom")
		(35 "F.Fab" user "Ref Des/Assembly Top")
		(33 "B.Fab" user "Ref Des/Assembly Bottom")
	)
	(footprint ""
		(layer "B.Cu")
		(at 445.4906 -64.7446 180)
		(property "Reference" "C2P13"
			(at 0 0 0)
			(layer "B.SilkS")
			(hide yes)
			(effects
				(font
					(size 1.27 1.27)
				)
				(justify mirror)
			)
		)
		(property "Value" ""
			(at 0 0 0)
			(layer "B.Fab")
			(effects
				(font
					(size 1.27 1.27)
				)
				(justify mirror)
			)
		)
		(duplicate_pad_numbers_are_jumpers no)
		(fp_poly
			(pts
				(xy -0.3048 -0.1016) (xy -0.3048 0.9906) (xy 0.3048 0.9906) (xy 0.3048 -0.1016)
			)
			(stroke
				(width 0)
				(type default)
			)
			(fill no)
			(layer "B.CrtYd")
		)
		(fp_line
			(start 0.3048 0.9906)
			(end -0.3048 0.9906)
			(stroke
				(width 0.1)
				(type default)
			)
			(layer "B.Fab")
		)
		(fp_line
			(start 0.3048 -0.1016)
			(end 0.3048 0.9906)
			(stroke
				(width 0.1)
				(type default)
			)
			(layer "B.Fab")
		)
		(fp_line
			(start -0.3048 0.9906)
			(end -0.3048 -0.1016)
			(stroke
				(width 0.1)
				(type default)
			)
			(layer "B.Fab")
		)
		(fp_line
			(start -0.3048 -0.1016)
			(end 0.3048 -0.1016)
			(stroke
				(width 0.1)
				(type default)
			)
			(layer "B.Fab")
		)
		(pad "1" smd rect
			(at 0 0)
			(size 0.508 0.508)
			(layers "B.Cu" "B.Mask" "B.Paste")
			(net "P12V_STBY")
		)
		(pad "2" smd rect
			(at 0 0.889)
			(size 0.508 0.508)
			(layers "B.Cu" "B.Mask" "B.Paste")
			(net "GND")
		)
		(zone
			(layer "B.Cu")
			(hatch none 0.5)
			(connect_pads
				(clearance 0)
			)
			(min_thickness 0.25)
			(keepout
				(tracks not_allowed)
				(vias allowed)
				(pads allowed)
				(copperpour not_allowed)
				(footprints allowed)
			)
			(placement
				(enabled no)
				(sheetname "")
			)
			(fill
				(thermal_gap 0.5)
				(thermal_bridge_width 0.5)
				(island_removal_mode 0)
			)
			(polygon
				(pts
					(xy 445.2366 -65.3796) (xy 445.7446 -65.3796) (xy 445.7446 -64.9986) (xy 445.2366 -64.9986)
				)
			)
		)
		(zone
			(layer "B.Cu")
			(hatch none 0.5)
			(connect_pads
				(clearance 0)
			)
			(min_thickness 0.25)
			(keepout
				(tracks allowed)
				(vias not_allowed)
				(pads allowed)
				(copperpour not_allowed)
				(footprints allowed)
			)
			(placement
				(enabled no)
				(sheetname "")
			)
			(fill
				(thermal_gap 0.5)
				(thermal_bridge_width 0.5)
				(island_removal_mode 0)
			)
			(polygon
				(pts
					(xy 445.2366 -64.9986) (xy 445.7446 -64.9986) (xy 445.7446 -65.3796) (xy 445.2366 -65.3796)
				)
			)
		)
	)
	(footprint ""
		(layer "B.Cu")
		(at 370.290852 -46.788578)
		(property "Reference" "U2T4"
			(at -5.093716 -1.536192 180)
			(unlocked yes)
			(layer "B.SilkS")
			(effects
				(font
					(size 0.7874 0.5842)
					(thickness 0.1524)
				)
				(justify left mirror)
			)
		)
		(property "Value" ""
			(at 0 0 0)
			(layer "B.Fab")
			(effects
				(font
					(size 1.27 1.27)
				)
				(justify mirror)
			)
		)
		(duplicate_pad_numbers_are_jumpers no)
		(fp_line
			(start -4.4323 -0.64008)
			(end -4.4323 4.52628)
			(stroke
				(width 0.1524)
				(type default)
			)
			(layer "B.SilkS")
		)
		(fp_line
			(start -4.4323 4.52628)
			(end -1.5367 4.52628)
			(stroke
				(width 0.1524)
				(type default)
			)
			(layer "B.SilkS")
		)
		(fp_line
			(start -3.302 0.49022)
			(end -3.302 -0.64008)
			(stroke
				(width 0.1524)
				(type default)
			)
			(layer "B.SilkS")
		)
		(fp_line
			(start -2.667 -0.64008)
			(end -2.667 0.49022)
			(stroke
				(width 0.1524)
				(type default)
			)
			(layer "B.SilkS")
		)
		(fp_line
			(start -2.667 0.49022)
			(end -3.302 0.49022)
			(stroke
				(width 0.1524)
				(type default)
			)
			(layer "B.SilkS")
		)
		(fp_line
			(start -1.5367 -0.64008)
			(end -4.4323 -0.64008)
			(stroke
				(width 0.1524)
				(type default)
			)
			(layer "B.SilkS")
		)
		(fp_line
			(start -1.5367 4.52628)
			(end -1.5367 -0.64008)
			(stroke
				(width 0.1524)
				(type default)
			)
			(layer "B.SilkS")
		)
		(fp_circle
			(center 1.324102 -0.479552)
			(end 1.451102 -0.479552)
			(stroke
				(width 0.254)
				(type default)
			)
			(fill no)
			(layer "B.SilkS")
		)
		(fp_poly
			(pts
				(xy -0.7366 4.54152) (xy -0.7366 -0.64008) (xy -4.7244 -0.64008) (xy -5.2324 -0.64008) (xy -5.2324 4.54152)
				(xy -4.7244 4.54152)
			)
			(stroke
				(width 0)
				(type default)
			)
			(fill no)
			(layer "B.CrtYd")
		)
		(fp_line
			(start -5.2324 -0.64008)
			(end -5.2324 4.54152)
			(stroke
				(width 0.1)
				(type default)
			)
			(layer "B.Fab")
		)
		(fp_line
			(start -5.2324 4.54152)
			(end -0.7366 4.54152)
			(stroke
				(width 0.1)
				(type default)
			)
			(layer "B.Fab")
		)
		(fp_line
			(start -3.302 0.49022)
			(end -3.302 -0.64008)
			(stroke
				(width 0.1)
				(type default)
			)
			(layer "B.Fab")
		)
		(fp_line
			(start -2.667 -0.64008)
			(end -2.667 0.49022)
			(stroke
				(width 0.1)
				(type default)
			)
			(layer "B.Fab")
		)
		(fp_line
			(start -2.667 0.49022)
			(end -3.302 0.49022)
			(stroke
				(width 0.1)
				(type default)
			)
			(layer "B.Fab")
		)
		(fp_line
			(start -0.7366 -0.64008)
			(end -5.2324 -0.64008)
			(stroke
				(width 0.1)
				(type default)
			)
			(layer "B.Fab")
		)
		(fp_line
			(start -0.7366 4.54152)
			(end -0.7366 -0.64008)
			(stroke
				(width 0.1)
				(type default)
			)
			(layer "B.Fab")
		)
		(fp_circle
			(center 1.612138 -0.684784)
			(end 1.739138 -0.684784)
			(stroke
				(width 0.254)
				(type default)
			)
			(fill no)
			(layer "B.Fab")
		)
		(pad "1" smd rect
			(at 0 0 180)
			(size 2.159 0.381)
			(layers "B.Cu" "B.Mask" "B.Paste")
			(net "PD_GTL2104_4_DIR")
		)
		(pad "2" smd rect
			(at 0 0.65024 180)
			(size 2.159 0.381)
			(layers "B.Cu" "B.Mask" "B.Paste")
			(net "H_CPU1_PROCHOT_G_R_N")
		)
		(pad "3" smd rect
			(at 0 1.30048 180)
			(size 2.159 0.381)
			(layers "B.Cu" "B.Mask" "B.Paste")
			(net "H_CPU0_PROCHOT_G_R_N")
		)
		(pad "4" smd rect
			(at 0 1.95072 180)
			(size 2.159 0.381)
			(layers "B.Cu" "B.Mask" "B.Paste")
			(net "P0V7_GTL2104_5_VREF")
		)
		(pad "5" smd rect
			(at 0 2.60096 180)
			(size 2.159 0.381)
			(layers "B.Cu" "B.Mask" "B.Paste")
			(net "H_CPU_ERR1_GTL_N")
		)
		(pad "6" smd rect
			(at 0 3.2512 180)
			(size 2.159 0.381)
			(layers "B.Cu" "B.Mask" "B.Paste")
			(net "H_CPU_ERR0_GTL_N")
		)
		(pad "7" smd rect
			(at 0 3.90144 180)
			(size 2.159 0.381)
			(layers "B.Cu" "B.Mask" "B.Paste")
			(net "GND")
		)
		(pad "8" smd rect
			(at -5.969 3.90144 180)
			(size 2.159 0.381)
			(layers "B.Cu" "B.Mask" "B.Paste")
			(net "GND")
		)
		(pad "9" smd rect
			(at -5.969 3.2512 180)
			(size 2.159 0.381)
			(layers "B.Cu" "B.Mask" "B.Paste")
			(net "FM_CPU_ERR0_LVT3_R_N")
		)
		(pad "10" smd rect
			(at -5.969 2.60096 180)
			(size 2.159 0.381)
			(layers "B.Cu" "B.Mask" "B.Paste")
			(net "FM_CPU_ERR1_LVT3_R_N")
		)
		(pad "11" smd rect
			(at -5.969 1.95072 180)
			(size 2.159 0.381)
			(layers "B.Cu" "B.Mask" "B.Paste")
			(net "GND")
		)
		(pad "12" smd rect
			(at -5.969 1.30048 180)
			(size 2.159 0.381)
			(layers "B.Cu" "B.Mask" "B.Paste")
			(net "FM_CPU0_PROCHOT_LVT3_R_N")
		)
		(pad "13" smd rect
			(at -5.969 0.65024 180)
			(size 2.159 0.381)
			(layers "B.Cu" "B.Mask" "B.Paste")
			(net "FM_CPU1_PROCHOT_LVT3_R_N")
		)
		(pad "14" smd rect
			(at -5.969 0 180)
			(size 2.159 0.381)
			(layers "B.Cu" "B.Mask" "B.Paste")
			(net "P3V3")
		)
	)
)
